# T6G (Grand Teton) — schematic netlist excerpt (pin names and nets, part order shuffled) for the footprints in the layout excerpt that follows; sources: Cadence DE-HDL packaged netlist, KiCad conversion of 04192023_DAF0TMB3IC0_F0TG_MB_C_brd_V02_OCP.brd

PC383  Q_CAP  0.22UF 16V 10% X7R  pkg 0402  page 218 : A = SW_PVDDCR_CPU1_P1_BOOT1_R ; B = SW_PVDDCR_CPU1_P1_BOOTR1
R4603  Q_RES  10K 1% CHIP  pkg 0402LF  page 248 : A = SMB_BMC_GPU_EN ; B = GND
H29  HOLE  EMPTY  pkg TH  page 230 : \1\ = NC

(kicad_pcb
	(version 20260206)
	(generator "pcbnew")
	(generator_version "10.0")
	(general
		(thickness 1.6)
		(legacy_teardrops no)
	)
	(paper "A4")
	(title_block
		(title "04192023_DAF0TMB3IC0_F0TG_MB_C_brd_V02_OCP.brd")
		(comment 1 "Grand Teton / footprints 1403-1405 of 8354")
	)
	(layers
		(0 "F.Cu" signal "TOP")
		(4 "In1.Cu" signal "GND")
		(6 "In2.Cu" signal "IN1")
		(8 "In3.Cu" signal "GND1")
		(10 "In4.Cu" signal "IN2")
		(12 "In5.Cu" signal "GND2")
		(14 "In6.Cu" signal "IN3")
		(16 "In7.Cu" signal "GND3")
		(18 "In8.Cu" signal "VCC")
		(20 "In9.Cu" signal "VCC1")
		(22 "In10.Cu" signal "GND4")
		(24 "In11.Cu" signal "IN4")
		(26 "In12.Cu" signal "GND5")
		(28 "In13.Cu" signal "IN5")
		(30 "In14.Cu" signal "GND6")
		(32 "In15.Cu" signal "IN6")
		(34 "In16.Cu" signal "GND7")
		(2 "B.Cu" signal "BOTTOM")
		(9 "F.Adhes" user "F.Adhesive")
		(11 "B.Adhes" user "B.Adhesive")
		(13 "F.Paste" user "Package Geometry/Pastemask Top")
		(15 "B.Paste" user "Package Geometry/Pastemask Bottom")
		(5 "F.SilkS" user "Ref Des/Silkscreen Top")
		(7 "B.SilkS" user "Ref Des/Silkscreen Bottom")
		(1 "F.Mask" user "Board Geometry/Soldermask Top")
		(3 "B.Mask" user "Board Geometry/Soldermask Bottom")
		(17 "Dwgs.User" user "User.Drawings")
		(19 "Cmts.User" user "User.Comments")
		(21 "Eco1.User" user "User.Eco1")
		(23 "Eco2.User" user "User.Eco2")
		(25 "Edge.Cuts" user "Board Geometry/Outline")
		(27 "Margin" user)
		(31 "F.CrtYd" user "Package Geometry/Place Bound Top")
		(29 "B.CrtYd" user "Package Geometry/Place Bound Bottom")
		(35 "F.Fab" user "Ref Des/Assembly Top")
		(33 "B.Fab" user "Ref Des/Assembly Bottom")
	)
	(footprint ""
		(layer "F.Cu")
		(at 88.908128 -339.630258 -90)
		(property "Reference" "PC383"
			(at 0 0 270)
			(layer "F.SilkS")
			(hide yes)
			(effects
				(font
					(size 1.27 1.27)
				)
			)
		)
		(property "Value" ""
			(at 0 0 270)
			(layer "F.Fab")
			(effects
				(font
					(size 1.27 1.27)
				)
			)
		)
		(duplicate_pad_numbers_are_jumpers no)
		(fp_line
			(start -0.7874 0.4064)
			(end -0.7874 -0.4064)
			(stroke
				(width 0.1524)
				(type default)
			)
			(layer "F.SilkS")
		)
		(fp_line
			(start 0.7874 0.4064)
			(end -0.7874 0.4064)
			(stroke
				(width 0.1524)
				(type default)
			)
			(layer "F.SilkS")
		)
		(fp_line
			(start -0.7874 -0.4064)
			(end 0.7874 -0.4064)
			(stroke
				(width 0.1524)
				(type default)
			)
			(layer "F.SilkS")
		)
		(fp_line
			(start 0.7874 -0.4064)
			(end 0.7874 0.4064)
			(stroke
				(width 0.1524)
				(type default)
			)
			(layer "F.SilkS")
		)
		(fp_line
			(start -0.67945 0.3048)
			(end -0.67945 -0.305054)
			(stroke
				(width 0.1)
				(type default)
			)
			(layer "F.Fab")
		)
		(fp_line
			(start -0.12065 0.3048)
			(end -0.67945 0.3048)
			(stroke
				(width 0.1)
				(type default)
			)
			(layer "F.Fab")
		)
		(fp_line
			(start 0.120396 0.3048)
			(end 0.120396 0.2794)
			(stroke
				(width 0.1)
				(type default)
			)
			(layer "F.Fab")
		)
		(fp_line
			(start 0.67945 0.3048)
			(end 0.120396 0.3048)
			(stroke
				(width 0.1)
				(type default)
			)
			(layer "F.Fab")
		)
		(fp_line
			(start -0.12065 0.2794)
			(end -0.12065 0.3048)
			(stroke
				(width 0.1)
				(type default)
			)
			(layer "F.Fab")
		)
		(fp_line
			(start 0.120396 0.2794)
			(end -0.12065 0.2794)
			(stroke
				(width 0.1)
				(type default)
			)
			(layer "F.Fab")
		)
		(fp_line
			(start -0.12065 -0.2794)
			(end 0.12065 -0.2794)
			(stroke
				(width 0.1)
				(type default)
			)
			(layer "F.Fab")
		)
		(fp_line
			(start 0.12065 -0.2794)
			(end 0.12065 -0.3048)
			(stroke
				(width 0.1)
				(type default)
			)
			(layer "F.Fab")
		)
		(fp_line
			(start 0.12065 -0.3048)
			(end 0.67945 -0.3048)
			(stroke
				(width 0.1)
				(type default)
			)
			(layer "F.Fab")
		)
		(fp_line
			(start 0.67945 -0.3048)
			(end 0.67945 0.3048)
			(stroke
				(width 0.1)
				(type default)
			)
			(layer "F.Fab")
		)
		(fp_line
			(start -0.67945 -0.305054)
			(end -0.12065 -0.305054)
			(stroke
				(width 0.1)
				(type default)
			)
			(layer "F.Fab")
		)
		(fp_line
			(start -0.12065 -0.305054)
			(end -0.12065 -0.2794)
			(stroke
				(width 0.1)
				(type default)
			)
			(layer "F.Fab")
		)
		(pad "1" smd circle
			(at -0.40005 0 270)
			(size 0 0)
			(layers "F.Cu" "F.Mask" "F.Paste")
			(net "SW_PVDDCR_CPU1_P1_BOOT1_R")
		)
		(pad "2" smd circle
			(at 0.40005 0 270)
			(size 0 0)
			(layers "F.Cu" "F.Mask" "F.Paste")
			(net "SW_PVDDCR_CPU1_P1_BOOTR1")
		)
	)
	(footprint ""
		(layer "F.Cu")
		(at 457.314046 -32.053276)
		(property "Reference" "H29"
			(at -5.8166 -5.552948 0)
			(unlocked yes)
			(layer "F.SilkS")
			(effects
				(font
					(size 0.7874 0.5842)
					(thickness 0.1524)
				)
				(justify left)
			)
		)
		(property "Value" ""
			(at 0 0 0)
			(layer "F.Fab")
			(effects
				(font
					(size 1.27 1.27)
				)
			)
		)
		(duplicate_pad_numbers_are_jumpers no)
		(fp_circle
			(center 0 0)
			(end 2.4003 0)
			(stroke
				(width 0.1524)
				(type default)
			)
			(fill no)
			(layer "F.SilkS")
		)
		(fp_circle
			(center 0 0)
			(end 6.5913 0)
			(stroke
				(width 0.1524)
				(type default)
			)
			(fill no)
			(layer "B.SilkS")
		)
		(fp_circle
			(center 0 0)
			(end 6.5913 0)
			(stroke
				(width 0.1)
				(type default)
			)
			(fill no)
			(layer "B.Fab")
		)
		(fp_circle
			(center 0 0)
			(end 2.4003 0)
			(stroke
				(width 0.1)
				(type default)
			)
			(fill no)
			(layer "F.Fab")
		)
		(pad "" np_thru_hole circle
			(at 0 0)
			(size 3.175 3.175)
			(drill 3.175)
			(layers "*.Cu" "*.Mask")
			(clearance 0.381)
			(thermal_gap 0.381)
		)
		(zone
			(layers "F.Cu" "B.Cu" "In1.Cu" "In2.Cu" "In3.Cu" "In4.Cu" "In5.Cu" "In6.Cu"
				"In7.Cu" "In8.Cu" "In9.Cu" "In10.Cu" "In11.Cu" "In12.Cu" "In13.Cu" "In14.Cu"
				"In15.Cu" "In16.Cu"
			)
			(hatch none 0.5)
			(connect_pads
				(clearance 0)
			)
			(min_thickness 0.25)
			(keepout
				(tracks not_allowed)
				(vias allowed)
				(pads allowed)
				(copperpour not_allowed)
				(footprints allowed)
			)
			(placement
				(enabled no)
				(sheetname "")
			)
			(fill
				(thermal_gap 0.5)
				(thermal_bridge_width 0.5)
				(island_removal_mode 0)
			)
			(polygon
				(pts
					(arc
						(start 459.409546 -32.053276)
						(mid 455.218546 -32.053276)
						(end 459.409546 -32.053276)
					)
				)
			)
		)
	)
	(footprint ""
		(layer "F.Cu")
		(at 29.464 -434.9623)
		(property "Reference" "R4603"
			(at 0 0 0)
			(layer "F.SilkS")
			(hide yes)
			(effects
				(font
					(size 1.27 1.27)
				)
			)
		)
		(property "Value" ""
			(at 0 0 0)
			(layer "F.Fab")
			(effects
				(font
					(size 1.27 1.27)
				)
			)
		)
		(duplicate_pad_numbers_are_jumpers no)
		(fp_line
			(start -0.7874 -0.4064)
			(end 0.7874 -0.4064)
			(stroke
				(width 0.1524)
				(type default)
			)
			(layer "F.SilkS")
		)
		(fp_line
			(start -0.7874 0.4064)
			(end -0.7874 -0.4064)
			(stroke
				(width 0.1524)
				(type default)
			)
			(layer "F.SilkS")
		)
		(fp_line
			(start 0.7874 -0.4064)
			(end 0.7874 0.4064)
			(stroke
				(width 0.1524)
				(type default)
			)
			(layer "F.SilkS")
		)
		(fp_line
			(start 0.7874 0.4064)
			(end -0.7874 0.4064)
			(stroke
				(width 0.1524)
				(type default)
			)
			(layer "F.SilkS")
		)
		(fp_line
			(start -0.67945 -0.305054)
			(end -0.12065 -0.305054)
			(stroke
				(width 0.1)
				(type default)
			)
			(layer "F.Fab")
		)
		(fp_line
			(start -0.67945 0.3048)
			(end -0.67945 -0.305054)
			(stroke
				(width 0.1)
				(type default)
			)
			(layer "F.Fab")
		)
		(fp_line
			(start -0.12065 -0.305054)
			(end -0.12065 -0.2794)
			(stroke
				(width 0.1)
				(type default)
			)
			(layer "F.Fab")
		)
		(fp_line
			(start -0.12065 -0.2794)
			(end 0.12065 -0.2794)
			(stroke
				(width 0.1)
				(type default)
			)
			(layer "F.Fab")
		)
		(fp_line
			(start -0.12065 0.2794)
			(end -0.12065 0.3048)
			(stroke
				(width 0.1)
				(type default)
			)
			(layer "F.Fab")
		)
		(fp_line
			(start -0.12065 0.3048)
			(end -0.67945 0.3048)
			(stroke
				(width 0.1)
				(type default)
			)
			(layer "F.Fab")
		)
		(fp_line
			(start 0.120396 0.2794)
			(end -0.12065 0.2794)
			(stroke
				(width 0.1)
				(type default)
			)
			(layer "F.Fab")
		)
		(fp_line
			(start 0.120396 0.3048)
			(end 0.120396 0.2794)
			(stroke
				(width 0.1)
				(type default)
			)
			(layer "F.Fab")
		)
		(fp_line
			(start 0.12065 -0.3048)
			(end 0.67945 -0.3048)
			(stroke
				(width 0.1)
				(type default)
			)
			(layer "F.Fab")
		)
		(fp_line
			(start 0.12065 -0.2794)
			(end 0.12065 -0.3048)
			(stroke
				(width 0.1)
				(type default)
			)
			(layer "F.Fab")
		)
		(fp_line
			(start 0.67945 -0.3048)
			(end 0.67945 0.3048)
			(stroke
				(width 0.1)
				(type default)
			)
			(layer "F.Fab")
		)
		(fp_line
			(start 0.67945 0.3048)
			(end 0.120396 0.3048)
			(stroke
				(width 0.1)
				(type default)
			)
			(layer "F.Fab")
		)
		(pad "1" smd circle
			(at -0.40005 0)
			(size 0 0)
			(layers "F.Cu" "F.Mask" "F.Paste")
			(net "SMB_BMC_GPU_EN")
		)
		(pad "2" smd circle
			(at 0.40005 0)
			(size 0 0)
			(layers "F.Cu" "F.Mask" "F.Paste")
			(net "GND")
		)
	)
)
